FILE_TYPE = MULTI_PHYS_TABLE;
PART 'FET_N'
{=====================================================================================================================================================================================================================}
:VALUE        | PACK_TYPE | MATERIAL | PART_NUMBER     = EnvComp                  |  PART_NUMBER | JEDEC_TYPE| ALT_SYMBOLS                          | CLASS | DESCRIPTION                       | HEIGHT | COMPONENT_TYPE | LEAD_LENGTH| LPID   | SPEED_URL | Status |RPL| AML | Bus_Unit | Days ;
{=====================================================================================================================================================================================================================}
'2N7002'      | 'SOT23LF' | 'FET'    | 'C79254-001'(!) = 'YES;YES;YES;UNK;ok;VLD' | 'C79254-001' | 'SOT23B'  | '()'                                 | 'IC'  | '2N7002 N-CHANNEL MOSFET'         | '.044 IN' |'SMALLSMT'      | ''      | '' | 'http://speed.intel.com:8081/speed/module/pdm/item/pdm_item_detail_direct.asp?item_cde=C79254-001&item_rev=01&url_param=unused' | 'Approved' | 'YES' | '12' | 'SMO_IC' | '112' 
'2N7002'      | 'SOT23'   | 'FET'    | 'C79254-001'(!) = 'YES;YES;YES;UNK;ok;VLD' | 'C79254-001' | 'SOT23B'  | '()'                                 | 'IC'  | '2N7002 N-CHANNEL MOSFET'         | '.044 IN' |'SMALLSMT'      | ''      | '' | 'http://speed.intel.com:8081/speed/module/pdm/item/pdm_item_detail_direct.asp?item_cde=C79254-001&item_rev=01&url_param=unused' | 'Approved' | 'YES' | '12' | 'SMO_IC' | '112' 
'2N7002'      | 'SOT23LF' | 'EMPTY'  | 'C79254-001'(!) = 'YES;YES;YES;UNK;ok;VLD' | 'C79254-001' | 'SOT23B'  | '()'                                 | 'IO'  | '2N7002 N-CHANNEL MOSFET'         | '.044 IN' |'SMALLSMT'      | ''      | '' | 'http://speed.intel.com:8081/speed/module/pdm/item/pdm_item_detail_direct.asp?item_cde=C79254-001&item_rev=01&url_param=unused' | 'Approved' | 'YES' | '12' | 'SMO_IC' | '112' 
'2N7002'      | 'SOT23'   | 'EMPTY'  | 'C79254-001'(!) = 'YES;YES;YES;UNK;ok;VLD' | 'C79254-001' | 'SOT23B'  | '()'                                 | 'IO'  | '2N7002 N-CHANNEL MOSFET'         | '.044 IN' |'SMALLSMT'      | ''      | '' | 'http://speed.intel.com:8081/speed/module/pdm/item/pdm_item_detail_direct.asp?item_cde=C79254-001&item_rev=01&url_param=unused' | 'Approved' | 'YES' | '12' | 'SMO_IC' | '112' 
END_PART
END.
